(kicad_pcb
	(version 20260206)
	(generator "pcbnew")
	(generator_version "10.0")
	(general
		(thickness 1.6)
		(legacy_teardrops no)
	)
	(paper "A4")
	(title_block
		(title "peb — Lightning_PEB_BRD.brd")
		(comment 1 "Lightning (Wiwynn / Facebook NVMe JBOF) / footprints 746-753 of 2563")
	)
	(layers
		(0 "F.Cu" signal "TOP")
		(4 "In1.Cu" signal "L2GND")
		(6 "In2.Cu" signal "L3")
		(8 "In3.Cu" signal "L4VCC")
		(10 "In4.Cu" signal "L5VCC")
		(12 "In5.Cu" signal "L6")
		(14 "In6.Cu" signal "L7GND")
		(2 "B.Cu" signal "BOTTOM")
		(9 "F.Adhes" user "F.Adhesive")
		(11 "B.Adhes" user "B.Adhesive")
		(13 "F.Paste" user "Package Geometry/Pastemask Top")
		(15 "B.Paste" user "Package Geometry/Pastemask Bottom")
		(5 "F.SilkS" user "Ref Des/Silkscreen Top")
		(7 "B.SilkS" user "Ref Des/Silkscreen Bottom")
		(1 "F.Mask" user "Board Geometry/Soldermask Top")
		(3 "B.Mask" user "Board Geometry/Soldermask Bottom")
		(17 "Dwgs.User" user "User.Drawings")
		(19 "Cmts.User" user "User.Comments")
		(21 "Eco1.User" user "User.Eco1")
		(23 "Eco2.User" user "User.Eco2")
		(25 "Edge.Cuts" user "Board Geometry/Outline")
		(27 "Margin" user)
		(31 "F.CrtYd" user "Package Geometry/Place Bound Top")
		(29 "B.CrtYd" user "Package Geometry/Place Bound Bottom")
		(35 "F.Fab" user "Ref Des/Assembly Top")
		(33 "B.Fab" user "Ref Des/Assembly Bottom")
	)
	(footprint ""
		(layer "F.Cu")
		(at 310.007 -68.5546)
		(property "Reference" "PG55"
			(at 0 0 0)
			(layer "F.SilkS")
			(hide yes)
			(effects
				(font
					(size 1.27 1.27)
				)
			)
		)
		(property "Value" "GAP-CLOSE-PWR-3-GP"
			(at 0.0254 -6.5786 0)
			(unlocked yes)
			(layer "F.Fab")
			(hide yes)
			(effects
				(font
					(size 1.016 1.016)
					(thickness 0.1524)
				)
			)
		)
		(property "Device Type" "GAP-CLOSE-PWR-3"
			(at 0.0254 -8.255 0)
			(unlocked yes)
			(layer "F.Fab")
			(hide yes)
			(effects
				(font
					(size 1.016 1.016)
					(thickness 0.1524)
				)
			)
		)
		(duplicate_pad_numbers_are_jumpers no)
		(fp_rect
			(start -0.7112 0.4572)
			(end 0.7112 -0.4572)
			(stroke
				(width 0)
				(type default)
			)
			(fill no)
			(layer "F.CrtYd")
		)
		(fp_poly
			(pts
				(xy -0.7112 -0.4572) (xy 0.7112 -0.4572) (xy 0.7112 0.4572) (xy -0.7112 0.4572)
			)
			(stroke
				(width 0)
				(type default)
			)
			(fill no)
			(layer "F.Fab")
		)
		(pad "1" smd rect
			(at -0.3048 0)
			(size 0.6604 0.762)
			(layers "F.Cu" "F.Mask" "F.Paste")
			(net "DUT_VDD")
		)
		(pad "2" smd rect
			(at 0.3048 0)
			(size 0.6604 0.762)
			(layers "F.Cu" "F.Mask" "F.Paste")
			(net "P0V9_E")
		)
	)
	(footprint ""
		(layer "F.Cu")
		(at 198.3994 -34.7726 180)
		(property "Reference" "R765"
			(at 0 0 180)
			(layer "F.SilkS")
			(hide yes)
			(effects
				(font
					(size 1.27 1.27)
				)
			)
		)
		(property "Value" "4K7R2F-GP"
			(at 0.064008 -3.993896 180)
			(unlocked yes)
			(layer "F.Fab")
			(hide yes)
			(effects
				(font
					(size 1.016 1.016)
					(thickness 0.1524)
				)
			)
		)
		(property "Device Type" "R402H16"
			(at 0.064008 -5.517896 180)
			(unlocked yes)
			(layer "F.Fab")
			(hide yes)
			(effects
				(font
					(size 1.016 1.016)
					(thickness 0.1524)
				)
			)
		)
		(duplicate_pad_numbers_are_jumpers no)
		(fp_line
			(start 0.508 -0.9398)
			(end -0.508 -0.9398)
			(stroke
				(width 0.1524)
				(type default)
			)
			(layer "F.SilkS")
		)
		(fp_line
			(start -0.508 -0.9398)
			(end -0.508 0.9398)
			(stroke
				(width 0.1524)
				(type default)
			)
			(layer "F.SilkS")
		)
		(fp_rect
			(start -0.508 0.9398)
			(end 0.508 -0.9398)
			(stroke
				(width 0)
				(type default)
			)
			(fill no)
			(layer "F.CrtYd")
		)
		(fp_rect
			(start -0.508 0.9398)
			(end 0.508 -0.9398)
			(stroke
				(width 0)
				(type default)
			)
			(fill no)
			(layer "F.Fab")
		)
		(pad "1" smd custom
			(at 0 -0.4445 180)
			(size 0.1397 0.1397)
			(layers "F.Cu" "F.Mask" "F.Paste")
			(net "U55_A0")
			(options
				(clearance outline)
				(anchor circle)
			)
			(primitives
				(gr_poly
					(pts
						(arc
							(start -0.1778 -0.2794)
							(mid -0.249642 -0.249642)
							(end -0.2794 -0.1778)
						)
						(arc
							(start -0.2794 0.1778)
							(mid -0.249642 0.249642)
							(end -0.1778 0.2794)
						)
						(arc
							(start 0.1778 0.2794)
							(mid 0.249642 0.249642)
							(end 0.2794 0.1778)
						)
						(arc
							(start 0.2794 -0.1778)
							(mid 0.249642 -0.249642)
							(end 0.1778 -0.2794)
						)
					)
					(width 0)
					(fill yes)
				)
			)
		)
		(pad "2" smd custom
			(at 0 0.4445 180)
			(size 0.1397 0.1397)
			(layers "F.Cu" "F.Mask" "F.Paste")
			(net "P3V3_STBY")
			(options
				(clearance outline)
				(anchor circle)
			)
			(primitives
				(gr_poly
					(pts
						(arc
							(start -0.1778 -0.2794)
							(mid -0.249642 -0.249642)
							(end -0.2794 -0.1778)
						)
						(arc
							(start -0.2794 0.1778)
							(mid -0.249642 0.249642)
							(end -0.1778 0.2794)
						)
						(arc
							(start 0.1778 0.2794)
							(mid 0.249642 0.249642)
							(end 0.2794 0.1778)
						)
						(arc
							(start 0.2794 -0.1778)
							(mid 0.249642 -0.249642)
							(end 0.1778 -0.2794)
						)
					)
					(width 0)
					(fill yes)
				)
			)
		)
	)
	(footprint ""
		(layer "F.Cu")
		(at 310.007 -67.0306)
		(property "Reference" "PG37"
			(at 0 0 0)
			(layer "F.SilkS")
			(hide yes)
			(effects
				(font
					(size 1.27 1.27)
				)
			)
		)
		(property "Value" "GAP-CLOSE-PWR-3-GP"
			(at 0.0254 -6.5786 0)
			(unlocked yes)
			(layer "F.Fab")
			(hide yes)
			(effects
				(font
					(size 1.016 1.016)
					(thickness 0.1524)
				)
			)
		)
		(property "Device Type" "GAP-CLOSE-PWR-3"
			(at 0.0254 -8.255 0)
			(unlocked yes)
			(layer "F.Fab")
			(hide yes)
			(effects
				(font
					(size 1.016 1.016)
					(thickness 0.1524)
				)
			)
		)
		(duplicate_pad_numbers_are_jumpers no)
		(fp_rect
			(start -0.7112 0.4572)
			(end 0.7112 -0.4572)
			(stroke
				(width 0)
				(type default)
			)
			(fill no)
			(layer "F.CrtYd")
		)
		(fp_poly
			(pts
				(xy -0.7112 -0.4572) (xy 0.7112 -0.4572) (xy 0.7112 0.4572) (xy -0.7112 0.4572)
			)
			(stroke
				(width 0)
				(type default)
			)
			(fill no)
			(layer "F.Fab")
		)
		(pad "1" smd rect
			(at -0.3048 0)
			(size 0.6604 0.762)
			(layers "F.Cu" "F.Mask" "F.Paste")
			(net "DUT_VDD")
		)
		(pad "2" smd rect
			(at 0.3048 0)
			(size 0.6604 0.762)
			(layers "F.Cu" "F.Mask" "F.Paste")
			(net "P0V9_E")
		)
	)
	(footprint ""
		(layer "F.Cu")
		(at 206.60995 -32.418274 90)
		(property "Reference" "R2979"
			(at 0 0 90)
			(layer "F.SilkS")
			(hide yes)
			(effects
				(font
					(size 1.27 1.27)
				)
			)
		)
		(property "Value" "0R2J-2-GP"
			(at 0.064008 -3.993896 90)
			(unlocked yes)
			(layer "F.Fab")
			(hide yes)
			(effects
				(font
					(size 1.016 1.016)
					(thickness 0.1524)
				)
			)
		)
		(property "Device Type" "R402H16"
			(at 0.064008 -5.517896 90)
			(unlocked yes)
			(layer "F.Fab")
			(hide yes)
			(effects
				(font
					(size 1.016 1.016)
					(thickness 0.1524)
				)
			)
		)
		(duplicate_pad_numbers_are_jumpers no)
		(fp_line
			(start 0.508 -0.9398)
			(end -0.508 -0.9398)
			(stroke
				(width 0.1524)
				(type default)
			)
			(layer "F.SilkS")
		)
		(fp_line
			(start -0.508 -0.9398)
			(end -0.508 0.9398)
			(stroke
				(width 0.1524)
				(type default)
			)
			(layer "F.SilkS")
		)
		(fp_rect
			(start -0.508 0.9398)
			(end 0.508 -0.9398)
			(stroke
				(width 0)
				(type default)
			)
			(fill no)
			(layer "F.CrtYd")
		)
		(fp_rect
			(start -0.508 0.9398)
			(end 0.508 -0.9398)
			(stroke
				(width 0)
				(type default)
			)
			(fill no)
			(layer "F.Fab")
		)
		(pad "1" smd custom
			(at 0 -0.4445 90)
			(size 0.1397 0.1397)
			(layers "F.Cu" "F.Mask" "F.Paste")
			(net "U55_SDA")
			(options
				(clearance outline)
				(anchor circle)
			)
			(primitives
				(gr_poly
					(pts
						(arc
							(start -0.1778 -0.2794)
							(mid -0.249642 -0.249642)
							(end -0.2794 -0.1778)
						)
						(arc
							(start -0.2794 0.1778)
							(mid -0.249642 0.249642)
							(end -0.1778 0.2794)
						)
						(arc
							(start 0.1778 0.2794)
							(mid 0.249642 0.249642)
							(end 0.2794 0.1778)
						)
						(arc
							(start 0.2794 -0.1778)
							(mid 0.249642 -0.249642)
							(end 0.1778 -0.2794)
						)
					)
					(width 0)
					(fill yes)
				)
			)
		)
		(pad "2" smd custom
			(at 0 0.4445 90)
			(size 0.1397 0.1397)
			(layers "F.Cu" "F.Mask" "F.Paste")
			(net "BMC_I2C11_MINI5_SDA_S")
			(options
				(clearance outline)
				(anchor circle)
			)
			(primitives
				(gr_poly
					(pts
						(arc
							(start -0.1778 -0.2794)
							(mid -0.249642 -0.249642)
							(end -0.2794 -0.1778)
						)
						(arc
							(start -0.2794 0.1778)
							(mid -0.249642 0.249642)
							(end -0.1778 0.2794)
						)
						(arc
							(start 0.1778 0.2794)
							(mid 0.249642 0.249642)
							(end 0.2794 0.1778)
						)
						(arc
							(start 0.2794 -0.1778)
							(mid 0.249642 -0.249642)
							(end 0.1778 -0.2794)
						)
					)
					(width 0)
					(fill yes)
				)
			)
		)
	)
	(footprint ""
		(layer "F.Cu")
		(at 49.17694 -147.03552)
		(property "Reference" "TP320"
			(at 0 0 0)
			(layer "F.SilkS")
			(hide yes)
			(effects
				(font
					(size 1.27 1.27)
				)
			)
		)
		(property "Value" "TPAD28-2-GP"
			(at -0.0127 -1.6637 0)
			(unlocked yes)
			(layer "F.Fab")
			(hide yes)
			(effects
				(font
					(size 1.016 1.016)
					(thickness 0.1524)
				)
			)
		)
		(property "Device Type" "TPAD28"
			(at -0.0127 -3.1877 0)
			(unlocked yes)
			(layer "F.Fab")
			(hide yes)
			(effects
				(font
					(size 1.016 1.016)
					(thickness 0.1524)
				)
			)
		)
		(duplicate_pad_numbers_are_jumpers no)
		(fp_poly
			(pts
				(arc
					(start 0.3556 0)
					(mid -0.3556 0)
					(end 0.3556 0)
				)
			)
			(stroke
				(width 0)
				(type default)
			)
			(fill no)
			(layer "F.CrtYd")
		)
		(fp_poly
			(pts
				(arc
					(start 0.6096 0)
					(mid -0.6096 0)
					(end 0.6096 0)
				)
			)
			(stroke
				(width 0)
				(type default)
			)
			(fill no)
			(layer "F.Fab")
		)
		(pad "1" smd circle
			(at 0 0)
			(size 0.7112 0.7112)
			(layers "F.Cu" "F.Mask" "F.Paste")
			(net "TP_GPIOO2")
		)
	)
	(footprint ""
		(layer "F.Cu")
		(at 57.1246 -28.2194)
		(property "Reference" "R569"
			(at 0 0 0)
			(layer "F.SilkS")
			(hide yes)
			(effects
				(font
					(size 1.27 1.27)
				)
			)
		)
		(property "Value" "4K7R2F-GP"
			(at 0.064008 -3.993896 0)
			(unlocked yes)
			(layer "F.Fab")
			(hide yes)
			(effects
				(font
					(size 1.016 1.016)
					(thickness 0.1524)
				)
			)
		)
		(property "Device Type" "R402H16"
			(at 0.064008 -5.517896 0)
			(unlocked yes)
			(layer "F.Fab")
			(hide yes)
			(effects
				(font
					(size 1.016 1.016)
					(thickness 0.1524)
				)
			)
		)
		(duplicate_pad_numbers_are_jumpers no)
		(fp_line
			(start -0.508 -0.9398)
			(end -0.508 0.9398)
			(stroke
				(width 0.1524)
				(type default)
			)
			(layer "F.SilkS")
		)
		(fp_line
			(start 0.508 -0.9398)
			(end -0.508 -0.9398)
			(stroke
				(width 0.1524)
				(type default)
			)
			(layer "F.SilkS")
		)
		(fp_rect
			(start -0.508 0.9398)
			(end 0.508 -0.9398)
			(stroke
				(width 0)
				(type default)
			)
			(fill no)
			(layer "F.CrtYd")
		)
		(fp_rect
			(start -0.508 0.9398)
			(end 0.508 -0.9398)
			(stroke
				(width 0)
				(type default)
			)
			(fill no)
			(layer "F.Fab")
		)
		(pad "1" smd custom
			(at 0 -0.4445)
			(size 0.1397 0.1397)
			(layers "F.Cu" "F.Mask" "F.Paste")
			(net "P3V3_STBY")
			(options
				(clearance outline)
				(anchor circle)
			)
			(primitives
				(gr_poly
					(pts
						(arc
							(start -0.1778 -0.2794)
							(mid -0.249642 -0.249642)
							(end -0.2794 -0.1778)
						)
						(arc
							(start -0.2794 0.1778)
							(mid -0.249642 0.249642)
							(end -0.1778 0.2794)
						)
						(arc
							(start 0.1778 0.2794)
							(mid 0.249642 0.249642)
							(end 0.2794 0.1778)
						)
						(arc
							(start 0.2794 -0.1778)
							(mid 0.249642 -0.249642)
							(end 0.1778 -0.2794)
						)
					)
					(width 0)
					(fill yes)
				)
			)
		)
		(pad "2" smd custom
			(at 0 0.4445)
			(size 0.1397 0.1397)
			(layers "F.Cu" "F.Mask" "F.Paste")
			(net "TRAY_RESET_N")
			(options
				(clearance outline)
				(anchor circle)
			)
			(primitives
				(gr_poly
					(pts
						(arc
							(start -0.1778 -0.2794)
							(mid -0.249642 -0.249642)
							(end -0.2794 -0.1778)
						)
						(arc
							(start -0.2794 0.1778)
							(mid -0.249642 0.249642)
							(end -0.1778 0.2794)
						)
						(arc
							(start 0.1778 0.2794)
							(mid 0.249642 0.249642)
							(end 0.2794 0.1778)
						)
						(arc
							(start 0.2794 -0.1778)
							(mid 0.249642 -0.249642)
							(end 0.1778 -0.2794)
						)
					)
					(width 0)
					(fill yes)
				)
			)
		)
	)
	(footprint ""
		(layer "F.Cu")
		(at 273.843496 -10.046716 -90)
		(property "Reference" "R2910"
			(at 0 0 270)
			(layer "F.SilkS")
			(hide yes)
			(effects
				(font
					(size 1.27 1.27)
				)
			)
		)
		(property "Value" "0R2J-2-GP"
			(at 0.064008 -3.993896 270)
			(unlocked yes)
			(layer "F.Fab")
			(hide yes)
			(effects
				(font
					(size 1.016 1.016)
					(thickness 0.1524)
				)
			)
		)
		(property "Device Type" "R402H16"
			(at 0.064008 -5.517896 270)
			(unlocked yes)
			(layer "F.Fab")
			(hide yes)
			(effects
				(font
					(size 1.016 1.016)
					(thickness 0.1524)
				)
			)
		)
		(duplicate_pad_numbers_are_jumpers no)
		(fp_line
			(start -0.508 -0.9398)
			(end -0.508 0.9398)
			(stroke
				(width 0.1524)
				(type default)
			)
			(layer "F.SilkS")
		)
		(fp_line
			(start 0.508 -0.9398)
			(end -0.508 -0.9398)
			(stroke
				(width 0.1524)
				(type default)
			)
			(layer "F.SilkS")
		)
		(fp_rect
			(start -0.508 0.9398)
			(end 0.508 -0.9398)
			(stroke
				(width 0)
				(type default)
			)
			(fill no)
			(layer "F.CrtYd")
		)
		(fp_rect
			(start -0.508 0.9398)
			(end 0.508 -0.9398)
			(stroke
				(width 0)
				(type default)
			)
			(fill no)
			(layer "F.Fab")
		)
		(pad "1" smd custom
			(at 0 -0.4445 270)
			(size 0.1397 0.1397)
			(layers "F.Cu" "F.Mask" "F.Paste")
			(net "CBL_PRSNT_N_5")
			(options
				(clearance outline)
				(anchor circle)
			)
			(primitives
				(gr_poly
					(pts
						(arc
							(start -0.1778 -0.2794)
							(mid -0.249642 -0.249642)
							(end -0.2794 -0.1778)
						)
						(arc
							(start -0.2794 0.1778)
							(mid -0.249642 0.249642)
							(end -0.1778 0.2794)
						)
						(arc
							(start 0.1778 0.2794)
							(mid 0.249642 0.249642)
							(end 0.2794 0.1778)
						)
						(arc
							(start 0.2794 -0.1778)
							(mid 0.249642 -0.249642)
							(end 0.1778 -0.2794)
						)
					)
					(width 0)
					(fill yes)
				)
			)
		)
		(pad "2" smd custom
			(at 0 0.4445 270)
			(size 0.1397 0.1397)
			(layers "F.Cu" "F.Mask" "F.Paste")
			(net "8644_SDA_R_5")
			(options
				(clearance outline)
				(anchor circle)
			)
			(primitives
				(gr_poly
					(pts
						(arc
							(start -0.1778 -0.2794)
							(mid -0.249642 -0.249642)
							(end -0.2794 -0.1778)
						)
						(arc
							(start -0.2794 0.1778)
							(mid -0.249642 0.249642)
							(end -0.1778 0.2794)
						)
						(arc
							(start 0.1778 0.2794)
							(mid 0.249642 0.249642)
							(end 0.2794 0.1778)
						)
						(arc
							(start 0.2794 -0.1778)
							(mid 0.249642 -0.249642)
							(end 0.1778 -0.2794)
						)
					)
					(width 0)
					(fill yes)
				)
			)
		)
	)
	(footprint ""
		(layer "F.Cu")
		(at 38.862 -56.896)
		(property "Reference" "U194"
			(at 0 0 0)
			(layer "F.SilkS")
			(hide yes)
			(effects
				(font
					(size 1.27 1.27)
				)
			)
		)
		(property "Value" "TPS2065DBVT-GP"
			(at 0 -5.1308 0)
			(unlocked yes)
			(layer "F.Fab")
			(hide yes)
			(effects
				(font
					(size 1.016 1.016)
					(thickness 0.1524)
				)
			)
		)
		(property "Device Type" "SOT-23-5H58"
			(at 0 -6.7564 0)
			(unlocked yes)
			(layer "F.Fab")
			(hide yes)
			(effects
				(font
					(size 1.016 1.016)
					(thickness 0.1524)
				)
			)
		)
		(duplicate_pad_numbers_are_jumpers no)
		(fp_line
			(start -1.778 -2.286)
			(end -1.778 2.286)
			(stroke
				(width 0.1524)
				(type default)
			)
			(layer "F.SilkS")
		)
		(fp_line
			(start -1.778 2.286)
			(end -0.254 2.286)
			(stroke
				(width 0.1524)
				(type default)
			)
			(layer "F.SilkS")
		)
		(fp_line
			(start -1.778 2.286)
			(end 1.778 2.286)
			(stroke
				(width 0.1524)
				(type default)
			)
			(layer "F.SilkS")
		)
		(fp_line
			(start -1.7272 2.2352)
			(end -1.7272 0.762)
			(stroke
				(width 0.3302)
				(type default)
			)
			(layer "F.SilkS")
		)
		(fp_line
			(start -0.7112 2.2352)
			(end -1.7272 2.2352)
			(stroke
				(width 0.3302)
				(type default)
			)
			(layer "F.SilkS")
		)
		(fp_line
			(start -0.254 2.286)
			(end 1.778 2.286)
			(stroke
				(width 0.1524)
				(type default)
			)
			(layer "F.SilkS")
		)
		(fp_line
			(start 1.778 -2.286)
			(end -1.778 -2.286)
			(stroke
				(width 0.1524)
				(type default)
			)
			(layer "F.SilkS")
		)
		(fp_line
			(start 1.778 2.286)
			(end 1.778 -2.286)
			(stroke
				(width 0.1524)
				(type default)
			)
			(layer "F.SilkS")
		)
		(fp_poly
			(pts
				(xy -0.9652 2.4384) (xy -1.3208 2.794) (xy -0.6096 2.794)
			)
			(stroke
				(width 0)
				(type default)
			)
			(fill yes)
			(layer "F.SilkS")
		)
		(fp_rect
			(start -1.778 2.286)
			(end 1.778 -2.286)
			(stroke
				(width 0)
				(type default)
			)
			(fill no)
			(layer "F.CrtYd")
		)
		(fp_rect
			(start -1.778 2.286)
			(end 1.778 -2.286)
			(stroke
				(width 0)
				(type default)
			)
			(fill no)
			(layer "F.Fab")
		)
		(pad "1" smd rect
			(at -0.94996 1.143)
			(size 0.508 1.524)
			(layers "F.Cu" "F.Mask" "F.Paste")
			(net "P5V_USB")
		)
		(pad "2" smd rect
			(at 0 1.143)
			(size 0.508 1.524)
			(layers "F.Cu" "F.Mask" "F.Paste")
			(net "GND")
		)
		(pad "3" smd rect
			(at 0.94996 1.143)
			(size 0.508 1.524)
			(layers "F.Cu" "F.Mask" "F.Paste")
			(net "USB_OC#")
		)
		(pad "4" smd rect
			(at 0.94996 -1.143)
			(size 0.508 1.524)
			(layers "F.Cu" "F.Mask" "F.Paste")
			(net "USB5V_EN")
		)
		(pad "5" smd rect
			(at -0.94996 -1.143)
			(size 0.508 1.524)
			(layers "F.Cu" "F.Mask" "F.Paste")
			(net "P5V_USB_BP1_F")
		)
	)
)
